(kicad_pcb
	(version 20241229)
	(generator "pcbnew")
	(generator_version "9.0")
	(general
		(thickness 1.6)
		(legacy_teardrops no)
	)
	(paper "A4")
	(title_block
		(title "OCuLink to PCIe adapter")
		(date "2025-06-18")
		(rev "1.0.0")
		(company "Antmicro Ltd")
		(comment 1 "www.antmicro.com")
		(comment 9 "footprints 150-154 of 159")
	)
	(layers
		(0 "F.Cu" signal)
		(4 "In1.Cu" signal)
		(6 "In2.Cu" signal)
		(2 "B.Cu" signal)
		(9 "F.Adhes" user "F.Adhesive")
		(11 "B.Adhes" user "B.Adhesive")
		(13 "F.Paste" user)
		(15 "B.Paste" user)
		(5 "F.SilkS" user "F.Silkscreen")
		(7 "B.SilkS" user "B.Silkscreen")
		(1 "F.Mask" user)
		(3 "B.Mask" user)
		(17 "Dwgs.User" user "User.Drawings")
		(19 "Cmts.User" user "User.Comments")
		(21 "Eco1.User" user "User.Eco1")
		(23 "Eco2.User" user "User.Eco2")
		(25 "Edge.Cuts" user)
		(27 "Margin" user)
		(31 "F.CrtYd" user "F.Courtyard")
		(29 "B.CrtYd" user "B.Courtyard")
		(35 "F.Fab" user)
		(33 "B.Fab" user)
	)
	(footprint "antmicro-footprints:R_0402_1005Metric"
		(layer "F.Cu")
		(at 146 64 180)
		(descr "Resistor SMD 0402")
		(tags "resistor SMD 0402")
		(property "Reference" "R58"
			(at -1.2 -0.7 0)
			(layer "F.SilkS")
			(effects
				(font
					(size 0.7 0.7)
					(thickness 0.15)
				)
				(justify right top)
			)
		)
		(property "Value" "R_50R_0402"
			(at -1.011843 1.772046 0)
			(layer "F.Fab")
			(effects
				(font
					(size 0.7 0.7)
					(thickness 0.15)
				)
				(justify right top)
			)
		)
		(property "Datasheet" "https://www.bourns.com/docs/product-datasheets/cr.pdf"
			(at 0 0 0)
			(layer "F.Fab")
			(hide yes)
			(effects
				(font
					(size 1.27 1.27)
					(thickness 0.15)
				)
			)
		)
		(property "Description" "SMD Chip Resistor"
			(at 0 0 0)
			(layer "F.Fab")
			(hide yes)
			(effects
				(font
					(size 1.27 1.27)
					(thickness 0.15)
				)
			)
		)
		(property "MPN" "CR0402-FX-50R0GLF"
			(at 0 0 180)
			(unlocked yes)
			(layer "F.Fab")
			(hide yes)
			(effects
				(font
					(size 1 1)
					(thickness 0.15)
				)
			)
		)
		(property "Manufacturer" "Bourns"
			(at 0 0 180)
			(unlocked yes)
			(layer "F.Fab")
			(hide yes)
			(effects
				(font
					(size 1 1)
					(thickness 0.15)
				)
			)
		)
		(property "License" "Apache-2.0"
			(at 0 0 180)
			(unlocked yes)
			(layer "F.Fab")
			(hide yes)
			(effects
				(font
					(size 1 1)
					(thickness 0.15)
				)
			)
		)
		(property "Author" "Antmicro"
			(at 0 0 180)
			(unlocked yes)
			(layer "F.Fab")
			(hide yes)
			(effects
				(font
					(size 1 1)
					(thickness 0.15)
				)
			)
		)
		(property "Val" "50R"
			(at 0 0 180)
			(unlocked yes)
			(layer "F.Fab")
			(hide yes)
			(effects
				(font
					(size 1 1)
					(thickness 0.15)
				)
			)
		)
		(property "Tolerance" "1%"
			(at 0 0 180)
			(unlocked yes)
			(layer "F.Fab")
			(hide yes)
			(effects
				(font
					(size 1 1)
					(thickness 0.15)
				)
			)
		)
		(sheetname "/PCIe-clock-generator/")
		(sheetfile "pcie-clock-generator.kicad_sch")
		(attr smd exclude_from_bom dnp)
		(fp_poly
			(pts
				(xy -0.925 -0.47) (xy 0.925 -0.47) (xy 0.925 0.47) (xy -0.925 0.47)
			)
			(stroke
				(width 0.05)
				(type default)
			)
			(fill no)
			(layer "F.CrtYd")
		)
		(fp_poly
			(pts
				(xy -0.5 -0.25) (xy 0.5 -0.25) (xy 0.5 0.25) (xy -0.5 0.25)
			)
			(stroke
				(width 0.15)
				(type solid)
			)
			(fill no)
			(layer "F.Fab")
		)
		(fp_text user "License: Apache-2.0"
			(at -0.949999 5.169 0)
			(layer "F.Fab")
			(effects
				(font
					(size 0.7 0.7)
					(thickness 0.15)
				)
				(justify right top)
			)
		)
		(fp_text user "${REFERENCE}"
			(at -0.95 3.168 0)
			(layer "F.Fab")
			(effects
				(font
					(size 0.7 0.7)
					(thickness 0.15)
				)
				(justify right top)
			)
		)
		(fp_text user "Author: Antmicro"
			(at -0.95 4.169 0)
			(layer "F.Fab")
			(effects
				(font
					(size 0.7 0.7)
					(thickness 0.15)
				)
				(justify right top)
			)
		)
		(pad "1" smd roundrect
			(at -0.48 0 180)
			(size 0.59 0.64)
			(layers "F.Cu" "F.Mask" "F.Paste")
			(roundrect_rratio 0.25)
			(net 66 "GND")
			(pintype "passive")
		)
		(pad "2" smd roundrect
			(at 0.48 0 180)
			(size 0.59 0.64)
			(layers "F.Cu" "F.Mask" "F.Paste")
			(roundrect_rratio 0.25)
			(net 178 "/PCIe-clock-generator/PCIe_{REF1}_R.CK+")
			(pintype "passive")
		)
	)
	(footprint "antmicro-footprints:R_0402_1005Metric"
		(layer "F.Cu")
		(at 148.152 93.999999)
		(descr "Resistor SMD 0402")
		(tags "resistor SMD 0402")
		(property "Reference" "R40"
			(at 1.248 0.400001 180)
			(layer "F.SilkS")
			(effects
				(font
					(size 0.7 0.7)
					(thickness 0.15)
				)
				(justify left bottom)
			)
		)
		(property "Value" "R_140k_0.1%_0402"
			(at -1.011843 1.772046 0)
			(layer "F.Fab")
			(effects
				(font
					(size 0.7 0.7)
					(thickness 0.15)
				)
				(justify left bottom)
			)
		)
		(property "Datasheet" "https://www.vishay.com/docs/28758/tnpw_e3.pdf"
			(at 0 0 0)
			(layer "F.Fab")
			(hide yes)
			(effects
				(font
					(size 1.27 1.27)
					(thickness 0.15)
				)
			)
		)
		(property "Description" "SMD Chip Resistor, Ceramic, 140 kohm, ± 0.1%, 62.5 mW, 0402 [1005 Metric], Thin Film, Precision resistors"
			(at 0 0 0)
			(layer "F.Fab")
			(hide yes)
			(effects
				(font
					(size 1.27 1.27)
					(thickness 0.15)
				)
			)
		)
		(property "MPN" "RT0402BRD07140KL"
			(at 0 0 0)
			(unlocked yes)
			(layer "F.Fab")
			(hide yes)
			(effects
				(font
					(size 1 1)
					(thickness 0.15)
				)
			)
		)
		(property "Val" "140k"
			(at 0 0 0)
			(unlocked yes)
			(layer "F.Fab")
			(hide yes)
			(effects
				(font
					(size 1 1)
					(thickness 0.15)
				)
			)
		)
		(property "Manufacturer" "YAGEO"
			(at 0 0 0)
			(unlocked yes)
			(layer "F.Fab")
			(hide yes)
			(effects
				(font
					(size 1 1)
					(thickness 0.15)
				)
			)
		)
		(property "Tolerance" "0.1%"
			(at 0 0 0)
			(unlocked yes)
			(layer "F.Fab")
			(hide yes)
			(effects
				(font
					(size 1 1)
					(thickness 0.15)
				)
			)
		)
		(property "License" "Apache-2.0"
			(at 0 0 0)
			(unlocked yes)
			(layer "F.Fab")
			(hide yes)
			(effects
				(font
					(size 1 1)
					(thickness 0.15)
				)
			)
		)
		(property "Author" "Antmicro"
			(at 0 0 0)
			(unlocked yes)
			(layer "F.Fab")
			(hide yes)
			(effects
				(font
					(size 1 1)
					(thickness 0.15)
				)
			)
		)
		(sheetname "/USB-PD/")
		(sheetfile "usb-pd.kicad_sch")
		(attr smd)
		(fp_rect
			(start -0.925 -0.47)
			(end 0.925 0.47)
			(stroke
				(width 0.05)
				(type default)
			)
			(fill no)
			(layer "F.CrtYd")
		)
		(fp_rect
			(start -0.5 -0.25)
			(end 0.5 0.25)
			(stroke
				(width 0.15)
				(type solid)
			)
			(fill no)
			(layer "F.Fab")
		)
		(fp_text user "License: Apache-2.0"
			(at -0.949999 5.169 0)
			(layer "F.Fab")
			(effects
				(font
					(size 0.7 0.7)
					(thickness 0.15)
				)
				(justify left bottom)
			)
		)
		(fp_text user "${REFERENCE}"
			(at 0 0 0)
			(layer "F.Fab")
			(effects
				(font
					(size 0.7 0.7)
					(thickness 0.15)
				)
				(justify left bottom)
			)
		)
		(fp_text user "Author: Antmicro"
			(at -0.95 4.169 0)
			(layer "F.Fab")
			(effects
				(font
					(size 0.7 0.7)
					(thickness 0.15)
				)
				(justify left bottom)
			)
		)
		(pad "1" smd roundrect
			(at -0.48 0)
			(size 0.59 0.64)
			(layers "F.Cu" "F.Mask" "F.Paste")
			(roundrect_rratio 0.25)
			(net 159 "/USB-PD/12V_FB")
			(pintype "passive")
		)
		(pad "2" smd roundrect
			(at 0.48 0)
			(size 0.59 0.64)
			(layers "F.Cu" "F.Mask" "F.Paste")
			(roundrect_rratio 0.25)
			(net 187 "/USB-PD/12V_CONV")
			(pintype "passive")
		)
	)
	(footprint "antmicro-footprints:LED_0603_1608Metric_G"
		(layer "F.Cu")
		(at 151.5 162.25)
		(descr "LED SMD 0603 Green")
		(tags "LED SMD 0603 Green")
		(property "Reference" "D1"
			(at -0.75 1.58 0)
			(layer "F.SilkS")
			(effects
				(font
					(size 0.7 0.7)
					(thickness 0.15)
				)
				(justify left bottom)
			)
		)
		(property "Value" "LED_G_0603_LTST-C190GKT"
			(at -0.001 1.599 0)
			(layer "F.Fab")
			(effects
				(font
					(size 0.7 0.7)
					(thickness 0.15)
				)
				(justify left bottom)
			)
		)
		(property "Datasheet" "https://media.digikey.com/pdf/Data%20Sheets/Lite-On%20PDFs/LTST-C190GKT.pdf"
			(at 0 0 0)
			(layer "F.Fab")
			(hide yes)
			(effects
				(font
					(size 1.27 1.27)
					(thickness 0.15)
				)
			)
		)
		(property "Description" "LED, Green, SMD, 0603, 20 mA, 2.1 V, 569 nm"
			(at 0 0 0)
			(layer "F.Fab")
			(hide yes)
			(effects
				(font
					(size 1.27 1.27)
					(thickness 0.15)
				)
			)
		)
		(property "MPN" "LTST-C190GKT"
			(at 0 0 0)
			(unlocked yes)
			(layer "F.Fab")
			(hide yes)
			(effects
				(font
					(size 1 1)
					(thickness 0.15)
				)
			)
		)
		(property "Manufacturer" "Lite-On"
			(at 0 0 0)
			(unlocked yes)
			(layer "F.Fab")
			(hide yes)
			(effects
				(font
					(size 1 1)
					(thickness 0.15)
				)
			)
		)
		(property "Color" "Green"
			(at 0 0 0)
			(unlocked yes)
			(layer "F.Fab")
			(hide yes)
			(effects
				(font
					(size 1 1)
					(thickness 0.15)
				)
			)
		)
		(property "Author" "Antmicro"
			(at 0 0 0)
			(unlocked yes)
			(layer "F.Fab")
			(hide yes)
			(effects
				(font
					(size 1 1)
					(thickness 0.15)
				)
			)
		)
		(property "License" "Apache-2.0"
			(at 0 0 0)
			(unlocked yes)
			(layer "F.Fab")
			(hide yes)
			(effects
				(font
					(size 1 1)
					(thickness 0.15)
				)
			)
		)
		(sheetname "/Power/")
		(sheetfile "power.kicad_sch")
		(attr smd)
		(fp_line
			(start -1.18 -0.319)
			(end -1.18 0.321)
			(stroke
				(width 0.15)
				(type solid)
			)
			(layer "F.SilkS")
		)
		(fp_line
			(start -0.094672 0.001008)
			(end -0.24 0.001008)
			(stroke
				(width 0.1)
				(type solid)
			)
			(layer "F.SilkS")
		)
		(fp_line
			(start -0.094672 0.001008)
			(end 0.105328 -0.198992)
			(stroke
				(width 0.1)
				(type solid)
			)
			(layer "F.SilkS")
		)
		(fp_line
			(start -0.094672 0.201008)
			(end -0.094672 -0.198992)
			(stroke
				(width 0.1)
				(type solid)
			)
			(layer "F.SilkS")
		)
		(fp_line
			(start 0.105328 0.001008)
			(end 0.24 0.001)
			(stroke
				(width 0.1)
				(type solid)
			)
			(layer "F.SilkS")
		)
		(fp_line
			(start 0.105328 0.201008)
			(end -0.094672 0.001008)
			(stroke
				(width 0.1)
				(type solid)
			)
			(layer "F.SilkS")
		)
		(fp_line
			(start 0.105328 0.201008)
			(end 0.105328 -0.198992)
			(stroke
				(width 0.1)
				(type solid)
			)
			(layer "F.SilkS")
		)
		(fp_line
			(start 0.22 -0.35)
			(end -0.22 -0.35)
			(stroke
				(width 0.15)
				(type solid)
			)
			(layer "F.SilkS")
		)
		(fp_line
			(start 0.22 0.35)
			(end -0.22 0.35)
			(stroke
				(width 0.15)
				(type solid)
			)
			(layer "F.SilkS")
		)
		(fp_rect
			(start 1.25 0.65)
			(end -1.25 -0.65)
			(stroke
				(width 0.05)
				(type solid)
			)
			(fill no)
			(layer "F.CrtYd")
		)
		(fp_line
			(start -0.199 -0.202)
			(end -0.199 0.1)
			(stroke
				(width 0.15)
				(type solid)
			)
			(layer "F.Fab")
		)
		(fp_line
			(start -0.199 0)
			(end -0.597 0)
			(stroke
				(width 0.15)
				(type solid)
			)
			(layer "F.Fab")
		)
		(fp_line
			(start -0.199 0.2)
			(end -0.199 0.1)
			(stroke
				(width 0.15)
				(type solid)
			)
			(layer "F.Fab")
		)
		(fp_line
			(start -0.101 0)
			(end 0.201 0.2)
			(stroke
				(width 0.15)
				(type solid)
			)
			(layer "F.Fab")
		)
		(fp_line
			(start 0.201 -0.202)
			(end -0.101 0)
			(stroke
				(width 0.15)
				(type solid)
			)
			(layer "F.Fab")
		)
		(fp_line
			(start 0.201 0)
			(end 0.201 -0.202)
			(stroke
				(width 0.15)
				(type solid)
			)
			(layer "F.Fab")
		)
		(fp_line
			(start 0.201 0.2)
			(end 0.201 0)
			(stroke
				(width 0.15)
				(type solid)
			)
			(layer "F.Fab")
		)
		(fp_line
			(start 0.599 0)
			(end 0.201 0)
			(stroke
				(width 0.15)
				(type solid)
			)
			(layer "F.Fab")
		)
		(fp_rect
			(start 0.848 0.4)
			(end -0.85 -0.402)
			(stroke
				(width 0.15)
				(type solid)
			)
			(fill no)
			(layer "F.Fab")
		)
		(fp_text user "${REFERENCE}"
			(at 0 0 0)
			(layer "F.Fab")
			(effects
				(font
					(size 0.7 0.7)
					(thickness 0.15)
				)
				(justify left bottom)
			)
		)
		(fp_text user "Author: Antmicro"
			(at -1.4224 4.799 0)
			(layer "F.Fab")
			(effects
				(font
					(size 0.7 0.7)
					(thickness 0.15)
				)
				(justify left bottom)
			)
		)
		(fp_text user "License: Apache-2.0"
			(at -1.4224 3.599 0)
			(layer "F.Fab")
			(effects
				(font
					(size 0.7 0.7)
					(thickness 0.15)
				)
				(justify left bottom)
			)
		)
		(pad "1" smd roundrect
			(at -0.7 0 180)
			(size 0.8 1)
			(layers "F.Cu" "F.Mask" "F.Paste")
			(roundrect_rratio 0.2)
			(net 89 "Net-(D1-C)")
			(pinfunction "C")
			(pintype "passive")
		)
		(pad "2" smd roundrect
			(at 0.7 0 180)
			(size 0.8 1)
			(layers "F.Cu" "F.Mask" "F.Paste")
			(roundrect_rratio 0.2)
			(net 87 "+12V")
			(pinfunction "A")
			(pintype "passive")
		)
	)
	(footprint "antmicro-footprints:C_0402_1005Metric"
		(layer "F.Cu")
		(at 139.3 42.9 -90)
		(descr "Capacitor SMD 0402")
		(tags "capacitor SMD 0402")
		(property "Reference" "C9"
			(at 0.9 0.5 90)
			(layer "F.SilkS")
			(effects
				(font
					(size 0.7 0.7)
					(thickness 0.15)
				)
				(justify right top)
			)
		)
		(property "Value" "C_4u7_25V_0402"
			(at -1.022927 2.155213 90)
			(layer "F.Fab")
			(effects
				(font
					(size 0.7 0.7)
					(thickness 0.15)
				)
				(justify right top)
			)
		)
		(property "Datasheet" "https://www.murata.com/products/productdetail?partno=GRM155C61E475ME15%23"
			(at 0 0 90)
			(layer "F.Fab")
			(hide yes)
			(effects
				(font
					(size 1.27 1.27)
					(thickness 0.15)
				)
			)
		)
		(property "Description" "SMD Multilayer Ceramic Capacitor"
			(at 0 0 90)
			(layer "F.Fab")
			(hide yes)
			(effects
				(font
					(size 1.27 1.27)
					(thickness 0.15)
				)
			)
		)
		(property "MPN" "GRM155C61E475ME15J"
			(at 0 0 270)
			(unlocked yes)
			(layer "F.Fab")
			(hide yes)
			(effects
				(font
					(size 1 1)
					(thickness 0.15)
				)
			)
		)
		(property "Manufacturer" "Murata"
			(at 0 0 270)
			(unlocked yes)
			(layer "F.Fab")
			(hide yes)
			(effects
				(font
					(size 1 1)
					(thickness 0.15)
				)
			)
		)
		(property "License" "Apache-2.0"
			(at 0 0 270)
			(unlocked yes)
			(layer "F.Fab")
			(hide yes)
			(effects
				(font
					(size 1 1)
					(thickness 0.15)
				)
			)
		)
		(property "Author" "Antmicro"
			(at 0 0 270)
			(unlocked yes)
			(layer "F.Fab")
			(hide yes)
			(effects
				(font
					(size 1 1)
					(thickness 0.15)
				)
			)
		)
		(property "Val" "4u7"
			(at 0 0 270)
			(unlocked yes)
			(layer "F.Fab")
			(hide yes)
			(effects
				(font
					(size 1 1)
					(thickness 0.15)
				)
			)
		)
		(property "Voltage" "25V"
			(at 0 0 270)
			(unlocked yes)
			(layer "F.Fab")
			(hide yes)
			(effects
				(font
					(size 1 1)
					(thickness 0.15)
				)
			)
		)
		(property "Dielectric" "X5S"
			(at 0 0 270)
			(unlocked yes)
			(layer "F.Fab")
			(hide yes)
			(effects
				(font
					(size 1 1)
					(thickness 0.15)
				)
			)
		)
		(sheetname "/USB-PD/")
		(sheetfile "usb-pd.kicad_sch")
		(attr smd)
		(fp_rect
			(start -0.925 -0.47)
			(end 0.925 0.47)
			(stroke
				(width 0.05)
				(type default)
			)
			(fill no)
			(layer "F.CrtYd")
		)
		(fp_line
			(start -0.494 0.248)
			(end -0.494 -0.25)
			(stroke
				(width 0.15)
				(type solid)
			)
			(layer "F.Fab")
		)
		(fp_line
			(start 0.504 0.248)
			(end -0.494 0.248)
			(stroke
				(width 0.15)
				(type solid)
			)
			(layer "F.Fab")
		)
		(fp_line
			(start -0.494 -0.25)
			(end 0.504 -0.25)
			(stroke
				(width 0.15)
				(type solid)
			)
			(layer "F.Fab")
		)
		(fp_line
			(start 0.504 -0.25)
			(end 0.504 0.248)
			(stroke
				(width 0.15)
				(type solid)
			)
			(layer "F.Fab")
		)
		(fp_text user "License: Apache-2.0"
			(at -0.939 5.799 90)
			(layer "F.Fab")
			(effects
				(font
					(size 0.7 0.7)
					(thickness 0.15)
				)
				(justify right top)
			)
		)
		(fp_text user "${REFERENCE}"
			(at 0 0 90)
			(layer "F.Fab")
			(effects
				(font
					(size 0.7 0.7)
					(thickness 0.15)
				)
				(justify right top)
			)
		)
		(fp_text user "Author: Antmicro"
			(at -0.939 3.399 90)
			(layer "F.Fab")
			(effects
				(font
					(size 0.7 0.7)
					(thickness 0.15)
				)
				(justify right top)
			)
		)
		(pad "1" smd roundrect
			(at -0.48 0 270)
			(size 0.59 0.64)
			(layers "F.Cu" "F.Mask" "F.Paste")
			(roundrect_rratio 0.25)
			(net 66 "GND")
			(pintype "passive")
		)
		(pad "2" smd roundrect
			(at 0.48 0 270)
			(size 0.59 0.64)
			(layers "F.Cu" "F.Mask" "F.Paste")
			(roundrect_rratio 0.25)
			(net 113 "VBUS")
			(pintype "passive")
		)
	)
	(footprint "antmicro-footprints:R_0402_1005Metric"
		(layer "F.Cu")
		(at 148.151999 95)
		(descr "Resistor SMD 0402")
		(tags "resistor SMD 0402")
		(property "Reference" "R39"
			(at 1.248001 0.4 180)
			(layer "F.SilkS")
			(effects
				(font
					(size 0.7 0.7)
					(thickness 0.15)
				)
				(justify left bottom)
			)
		)
		(property "Value" "R_10k_0.1%_0402"
			(at -1.011843 1.772046 0)
			(layer "F.Fab")
			(effects
				(font
					(size 0.7 0.7)
					(thickness 0.15)
				)
				(justify left bottom)
			)
		)
		(property "Datasheet" "https://www.mouser.com/datasheet/2/54/CRT-1649066.pdf"
			(at 0 0 0)
			(layer "F.Fab")
			(hide yes)
			(effects
				(font
					(size 1.27 1.27)
					(thickness 0.15)
				)
			)
		)
		(property "Description" "SMD Chip Resistor, 10 kohm, ± 0.1%, 62.5 mW, 0402 [1005 Metric], Thin Film, Precision Resistors"
			(at 0 0 0)
			(layer "F.Fab")
			(hide yes)
			(effects
				(font
					(size 1.27 1.27)
					(thickness 0.15)
				)
			)
		)
		(property "MPN" "CRT0402-BY-1002GLF "
			(at 0 0 0)
			(unlocked yes)
			(layer "F.Fab")
			(hide yes)
			(effects
				(font
					(size 1 1)
					(thickness 0.15)
				)
			)
		)
		(property "Val" "10k"
			(at 0 0 0)
			(unlocked yes)
			(layer "F.Fab")
			(hide yes)
			(effects
				(font
					(size 1 1)
					(thickness 0.15)
				)
			)
		)
		(property "Manufacturer" "Bourns"
			(at 0 0 0)
			(unlocked yes)
			(layer "F.Fab")
			(hide yes)
			(effects
				(font
					(size 1 1)
					(thickness 0.15)
				)
			)
		)
		(property "Tolerance" "0.1%"
			(at 0 0 0)
			(unlocked yes)
			(layer "F.Fab")
			(hide yes)
			(effects
				(font
					(size 1 1)
					(thickness 0.15)
				)
			)
		)
		(property "License" "Apache-2.0"
			(at 0 0 0)
			(unlocked yes)
			(layer "F.Fab")
			(hide yes)
			(effects
				(font
					(size 1 1)
					(thickness 0.15)
				)
			)
		)
		(property "Author" "Antmicro"
			(at 0 0 0)
			(unlocked yes)
			(layer "F.Fab")
			(hide yes)
			(effects
				(font
					(size 1 1)
					(thickness 0.15)
				)
			)
		)
		(sheetname "/USB-PD/")
		(sheetfile "usb-pd.kicad_sch")
		(attr smd)
		(fp_rect
			(start -0.925 -0.47)
			(end 0.925 0.47)
			(stroke
				(width 0.05)
				(type default)
			)
			(fill no)
			(layer "F.CrtYd")
		)
		(fp_rect
			(start -0.5 -0.25)
			(end 0.5 0.25)
			(stroke
				(width 0.15)
				(type solid)
			)
			(fill no)
			(layer "F.Fab")
		)
		(fp_text user "License: Apache-2.0"
			(at -0.949999 5.169 0)
			(layer "F.Fab")
			(effects
				(font
					(size 0.7 0.7)
					(thickness 0.15)
				)
				(justify left bottom)
			)
		)
		(fp_text user "Author: Antmicro"
			(at -0.95 4.169 0)
			(layer "F.Fab")
			(effects
				(font
					(size 0.7 0.7)
					(thickness 0.15)
				)
				(justify left bottom)
			)
		)
		(fp_text user "${REFERENCE}"
			(at 0 0 0)
			(layer "F.Fab")
			(effects
				(font
					(size 0.7 0.7)
					(thickness 0.15)
				)
				(justify left bottom)
			)
		)
		(pad "1" smd roundrect
			(at -0.48 0)
			(size 0.59 0.64)
			(layers "F.Cu" "F.Mask" "F.Paste")
			(roundrect_rratio 0.25)
			(net 66 "GND")
			(pintype "passive")
		)
		(pad "2" smd roundrect
			(at 0.48 0)
			(size 0.59 0.64)
			(layers "F.Cu" "F.Mask" "F.Paste")
			(roundrect_rratio 0.25)
			(net 159 "/USB-PD/12V_FB")
			(pintype "passive")
		)
	)
)
